# SCM (Grand Teton) — schematic netlist excerpt (pin names and nets, part order shuffled) for the footprints in the layout excerpt that follows; sources: Cadence DE-HDL packaged netlist, KiCad conversion of 12092022_DA0F0TMDCD0_F0T_Management_Board_D_brd_V3_OCP.brd

U56  AP2205W57  AP2205-W5-7 IC  pkg SOT25-5_0-95_2-96X1-6  page 51
  VIN  = P12V_AUX
  GND  = GND
  EN  = P12V_AUX
  \adj||nc\  = U56_ADJ_1
  VOUT  = P3V3_LDO

R116  Q_RES  4.7K 1% CHIP  pkg 0402LF  page 12 : A = PGPPA_BMC_AUX ; B = IRQ_BMC_LPC_SERIRQ_ESPI_GF

(kicad_pcb
	(version 20260206)
	(generator "pcbnew")
	(generator_version "10.0")
	(general
		(thickness 1.6)
		(legacy_teardrops no)
	)
	(paper "A4")
	(title_block
		(title "12092022_DA0F0TMDCD0_F0T_Management_Board_D_brd_V3_OCP.brd")
		(comment 1 "Grand Teton / footprints 552-553 of 1440")
	)
	(layers
		(0 "F.Cu" signal "TOP")
		(4 "In1.Cu" signal "GND")
		(6 "In2.Cu" signal "IN1")
		(8 "In3.Cu" signal "GND1")
		(10 "In4.Cu" signal "IN2")
		(12 "In5.Cu" signal "VCC")
		(14 "In6.Cu" signal "VCC1")
		(16 "In7.Cu" signal "IN3")
		(18 "In8.Cu" signal "GND2")
		(20 "In9.Cu" signal "IN4")
		(22 "In10.Cu" signal "GND3")
		(2 "B.Cu" signal "BOTTOM")
		(9 "F.Adhes" user "F.Adhesive")
		(11 "B.Adhes" user "B.Adhesive")
		(13 "F.Paste" user "Package Geometry/Pastemask Top")
		(15 "B.Paste" user "Package Geometry/Pastemask Bottom")
		(5 "F.SilkS" user "Ref Des/Silkscreen Top")
		(7 "B.SilkS" user "Ref Des/Silkscreen Bottom")
		(1 "F.Mask" user "Board Geometry/Soldermask Top")
		(3 "B.Mask" user "Board Geometry/Soldermask Bottom")
		(17 "Dwgs.User" user "User.Drawings")
		(19 "Cmts.User" user "User.Comments")
		(21 "Eco1.User" user "User.Eco1")
		(23 "Eco2.User" user "User.Eco2")
		(25 "Edge.Cuts" user "Board Geometry/Outline")
		(27 "Margin" user)
		(31 "F.CrtYd" user "Package Geometry/Place Bound Top")
		(29 "B.CrtYd" user "Package Geometry/Place Bound Bottom")
		(35 "F.Fab" user "Ref Des/Assembly Top")
		(33 "B.Fab" user "Ref Des/Assembly Bottom")
	)
	(footprint ""
		(layer "F.Cu")
		(at 76.581 -82.677 -90)
		(property "Reference" "U56"
			(at 1.5494 2.149348 90)
			(unlocked yes)
			(layer "F.SilkS")
			(effects
				(font
					(size 0.7874 0.5842)
					(thickness 0.1524)
				)
				(justify left)
			)
		)
		(property "Value" ""
			(at 0 0 270)
			(layer "F.Fab")
			(effects
				(font
					(size 1.27 1.27)
				)
			)
		)
		(duplicate_pad_numbers_are_jumpers no)
		(fp_line
			(start -1.934972 1.549908)
			(end 1.934972 1.549908)
			(stroke
				(width 0.1524)
				(type default)
			)
			(layer "F.SilkS")
		)
		(fp_line
			(start 1.934972 1.549908)
			(end 1.934972 -1.549908)
			(stroke
				(width 0.1524)
				(type default)
			)
			(layer "F.SilkS")
		)
		(fp_line
			(start 0 -0.82042)
			(end -0.475742 -1.549908)
			(stroke
				(width 0.1524)
				(type default)
			)
			(layer "F.SilkS")
		)
		(fp_line
			(start -1.934972 -1.549908)
			(end -1.934972 1.549908)
			(stroke
				(width 0.1524)
				(type default)
			)
			(layer "F.SilkS")
		)
		(fp_line
			(start -0.475742 -1.549908)
			(end -1.934972 -1.549908)
			(stroke
				(width 0.1524)
				(type default)
			)
			(layer "F.SilkS")
		)
		(fp_line
			(start 0.475742 -1.549908)
			(end 0 -0.82042)
			(stroke
				(width 0.1524)
				(type default)
			)
			(layer "F.SilkS")
		)
		(fp_line
			(start 1.934972 -1.549908)
			(end 0.475742 -1.549908)
			(stroke
				(width 0.1524)
				(type default)
			)
			(layer "F.SilkS")
		)
		(fp_poly
			(pts
				(xy -3.160522 -1.45796) (xy -3.160522 -0.44196) (xy -2.144522 -0.94996)
			)
			(stroke
				(width 0)
				(type default)
			)
			(fill yes)
			(layer "F.SilkS")
		)
		(fp_line
			(start -0.849884 1.549908)
			(end 0.849884 1.549908)
			(stroke
				(width 0.1)
				(type default)
			)
			(layer "F.Fab")
		)
		(fp_line
			(start 0.849884 1.549908)
			(end 0.849884 -1.549908)
			(stroke
				(width 0.1)
				(type default)
			)
			(layer "F.Fab")
		)
		(fp_line
			(start -0.849884 -1.549908)
			(end -0.849884 1.549908)
			(stroke
				(width 0.1)
				(type default)
			)
			(layer "F.Fab")
		)
		(fp_line
			(start 0.849884 -1.549908)
			(end -0.849884 -1.549908)
			(stroke
				(width 0.1)
				(type default)
			)
			(layer "F.Fab")
		)
		(fp_poly
			(pts
				(xy -3.160522 -1.45796) (xy -3.160522 -0.44196) (xy -2.144522 -0.94996)
			)
			(stroke
				(width 0)
				(type default)
			)
			(fill yes)
			(layer "F.Fab")
		)
		(pad "1" smd rect
			(at -1.299972 -0.94996 180)
			(size 0.7112 1.016)
			(layers "F.Cu" "F.Mask" "F.Paste")
			(net "P12V_AUX")
		)
		(pad "2" smd rect
			(at -1.299972 0 180)
			(size 0.7112 1.016)
			(layers "F.Cu" "F.Mask" "F.Paste")
			(net "GND")
		)
		(pad "3" smd rect
			(at -1.299972 0.94996 180)
			(size 0.7112 1.016)
			(layers "F.Cu" "F.Mask" "F.Paste")
			(net "P12V_AUX")
		)
		(pad "4" smd rect
			(at 1.299972 0.94996 180)
			(size 0.7112 1.016)
			(layers "F.Cu" "F.Mask" "F.Paste")
			(net "U56_ADJ_1")
		)
		(pad "5" smd rect
			(at 1.299972 -0.94996 180)
			(size 0.7112 1.016)
			(layers "F.Cu" "F.Mask" "F.Paste")
			(net "P3V3_LDO")
		)
	)
	(footprint ""
		(layer "F.Cu")
		(at 63.105792 -65.37071)
		(property "Reference" "R116"
			(at 0 0 0)
			(layer "F.SilkS")
			(hide yes)
			(effects
				(font
					(size 1.27 1.27)
				)
			)
		)
		(property "Value" ""
			(at 0 0 0)
			(layer "F.Fab")
			(effects
				(font
					(size 1.27 1.27)
				)
			)
		)
		(duplicate_pad_numbers_are_jumpers no)
		(fp_line
			(start -0.7874 -0.4064)
			(end 0.7874 -0.4064)
			(stroke
				(width 0.1524)
				(type default)
			)
			(layer "F.SilkS")
		)
		(fp_line
			(start -0.7874 0.4064)
			(end -0.7874 -0.4064)
			(stroke
				(width 0.1524)
				(type default)
			)
			(layer "F.SilkS")
		)
		(fp_line
			(start 0.7874 -0.4064)
			(end 0.7874 0.4064)
			(stroke
				(width 0.1524)
				(type default)
			)
			(layer "F.SilkS")
		)
		(fp_line
			(start 0.7874 0.4064)
			(end -0.7874 0.4064)
			(stroke
				(width 0.1524)
				(type default)
			)
			(layer "F.SilkS")
		)
		(fp_line
			(start -0.67945 -0.305054)
			(end -0.12065 -0.305054)
			(stroke
				(width 0.1)
				(type default)
			)
			(layer "F.Fab")
		)
		(fp_line
			(start -0.67945 0.3048)
			(end -0.67945 -0.305054)
			(stroke
				(width 0.1)
				(type default)
			)
			(layer "F.Fab")
		)
		(fp_line
			(start -0.12065 -0.305054)
			(end -0.12065 -0.2794)
			(stroke
				(width 0.1)
				(type default)
			)
			(layer "F.Fab")
		)
		(fp_line
			(start -0.12065 -0.2794)
			(end 0.12065 -0.2794)
			(stroke
				(width 0.1)
				(type default)
			)
			(layer "F.Fab")
		)
		(fp_line
			(start -0.12065 0.2794)
			(end -0.12065 0.3048)
			(stroke
				(width 0.1)
				(type default)
			)
			(layer "F.Fab")
		)
		(fp_line
			(start -0.12065 0.3048)
			(end -0.67945 0.3048)
			(stroke
				(width 0.1)
				(type default)
			)
			(layer "F.Fab")
		)
		(fp_line
			(start 0.120396 0.2794)
			(end -0.12065 0.2794)
			(stroke
				(width 0.1)
				(type default)
			)
			(layer "F.Fab")
		)
		(fp_line
			(start 0.120396 0.3048)
			(end 0.120396 0.2794)
			(stroke
				(width 0.1)
				(type default)
			)
			(layer "F.Fab")
		)
		(fp_line
			(start 0.12065 -0.3048)
			(end 0.67945 -0.3048)
			(stroke
				(width 0.1)
				(type default)
			)
			(layer "F.Fab")
		)
		(fp_line
			(start 0.12065 -0.2794)
			(end 0.12065 -0.3048)
			(stroke
				(width 0.1)
				(type default)
			)
			(layer "F.Fab")
		)
		(fp_line
			(start 0.67945 -0.3048)
			(end 0.67945 0.3048)
			(stroke
				(width 0.1)
				(type default)
			)
			(layer "F.Fab")
		)
		(fp_line
			(start 0.67945 0.3048)
			(end 0.120396 0.3048)
			(stroke
				(width 0.1)
				(type default)
			)
			(layer "F.Fab")
		)
		(pad "1" smd circle
			(at -0.40005 0)
			(size 0 0)
			(layers "F.Cu" "F.Mask" "F.Paste")
			(net "PGPPA_BMC_AUX")
		)
		(pad "2" smd circle
			(at 0.40005 0)
			(size 0 0)
			(layers "F.Cu" "F.Mask" "F.Paste")
			(net "IRQ_BMC_LPC_SERIRQ_ESPI_GF")
		)
	)
)
